FILE_TYPE = CONNECTIVITY;
{Allegro Design Entry HDL 17.4-2019 S026 (4007227) 1/17/2022}
"PAGE_NUMBER" = 143;
0"NC";
1"P3V3_AUX\g";
2"GND\g";
3"GND\g";
4"P3V3_AUX\g";
5"P3V3_AUX\g";
6"GND\g";
7"GND\g";
8"GND\g";
9"GND\g";
10"GND\g";
11"GND\g";
12"P3V3_AUX\g";
13"P5V_AUX\g";
14"P5V_AUX\g";
15"GND\g";
16"GND\g";
17"P1V8_AUX\g";
18"P12V_ALL_PWROK_N";
19"PU_P12V_ALL_PWROK_LED";
20"SMERR_LED";
21"SMERR_LED_N";
22"P12V_ALL_PWROK";
23"PU_SMERR_LED";
24"P5V_STBY_PWR_LED";
25"P3V3_AUX\g";
26"BOOT_RDY_BUF_LED";
27"BOOT_RDY_LED_N";
28"BOOT_RDY_LED";
29"PU_BOOT_RDY_LED";
30"P3V3_AUX\g";
31"P1V8_AUX\g";
32"BOOT_RDY_H";
33"BOOT_RDY_R1_N";
34"FM_SMERR_BUF_LED_N";
35"FM_SMERR_BUF_R_LED_N";
36"BOOT_RDY_BUF_R_LED";
37"FM_BIOS_POST_CMPLT_N";
38"FM_SMERR_LED_N";
%"UNIVERSAL_POWER"
"1","(-1875,5725)","0","pure_quanta_power","I1";
;
HDL_POWER"P3V3_AUX"
BOM_COST"OCP3.0 "
CDS_LIB"pure_quanta_power";
"A"25;
%"UNIVERSAL_POWER"
"1","(-4100,4150)","0","pure_quanta_power","I10";
;
HDL_POWER"P3V3_AUX"
BOM_COST"OCP3.0 "
CDS_LIB"pure_quanta_power";
"A"1;
%"Q_RES"
"2","(-4100,3800)","0","pure_quanta","I11";
;
LOCATION"R947"
$SEC"1"
CDS_SEC"1"
VALUE"4.7K"
MATERIAL"CHIP"
TOLERANCE"5%"
WATTAGE"1/16W"
PACK_TYPE"0402LF"
BOM_COST"OCP3.0 "
CDS_LIB"pure_quanta"
PART_NUMBER"CS24702JB10";
"A"
$PN"1"1;
"B"
$PN"2"20;
%"GND"
"1","(-4150,3550)","1","pure_quanta_power","I12";
;
SIZE"1B"
BOM_COST"MEM"
CDS_LIB"pure_quanta_power"
HDL_POWER"GND";
"A<SIZE-1..0>\NAC"2;
%"GND"
"1","(-4775,5175)","5","pure_quanta_power","I13";
;
BOM_COST"MEM"
SIZE"1B"
CDS_LIB"pure_quanta_power"
HDL_POWER"GND";
"A<SIZE-1..0>\NAC"3;
%"UNIVERSAL_POWER"
"1","(-4950,5775)","0","pure_quanta_power","I14";
;
HDL_POWER"P3V3_AUX"
BOM_COST"OCP3.0 "
CDS_LIB"pure_quanta_power";
"A"4;
%"Q_RES"
"2","(-4950,5425)","0","pure_quanta","I15";
;
LOCATION"R944"
$SEC"1"
CDS_SEC"1"
TOLERANCE"5%"
MATERIAL"CHIP"
WATTAGE"1/16W"
VALUE"4.7K"
PACK_TYPE"0402LF"
BOM_COST"OCP3.0 "
CDS_LIB"pure_quanta"
PART_NUMBER"CS24702JB10";
"A"
$PN"1"4;
"B"
$PN"2"26;
%"MOSFET_DUAL_6P"
"1","(-4400,5125)","0","pure_quanta","I16";
;
LOCATION"Q2"
$SEC"1"
CDS_SEC"1"
MATERIAL"IC"
PART_TYPE"SMLF"
VALUE"2N7002KDW"
CDS_LIB"pure_quanta"
CDS_LMAN_SYM_OUTLINE"-150,100,150,-100"
NEEDS_NO_SIZE"TRUE"
PART_NUMBER"BAM70020047";
"D2"
$PN"3"27;
"D1"
$PN"6"28;
"S2"
$PN"4"16;
"S1"
$PN"1"3;
"G2"
$PN"5"28;
"G1"
$PN"2"26;
%"UNIVERSAL_POWER"
"1","(-5100,4150)","0","pure_quanta_power","I17";
;
HDL_POWER"P3V3_AUX"
BOM_COST"OCP3.0 "
CDS_LIB"pure_quanta_power";
"A"5;
%"Q_RES"
"2","(-5100,3800)","0","pure_quanta","I18";
;
LOCATION"R945"
$SEC"1"
CDS_SEC"1"
MATERIAL"CHIP"
TOLERANCE"5%"
WATTAGE"1/16W"
VALUE"4.7K"
PACK_TYPE"0402LF"
BOM_COST"OCP3.0 "
CDS_LIB"pure_quanta"
PART_NUMBER"CS24702JB10";
"A"
$PN"1"5;
"B"
$PN"2"35;
%"MOSFET_DUAL_6P"
"1","(-4550,3500)","0","pure_quanta","I19";
;
LOCATION"Q11"
$SEC"1"
CDS_SEC"1"
PART_TYPE"SMLF"
MATERIAL"IC"
VALUE"2N7002KDW"
CDS_LIB"pure_quanta"
CDS_LMAN_SYM_OUTLINE"-150,100,150,-100"
NEEDS_NO_SIZE"TRUE"
PART_NUMBER"BAM70020047";
"D2"
$PN"3"21;
"D1"
$PN"6"20;
"S2"
$PN"4"2;
"S1"
$PN"1"6;
"G2"
$PN"5"20;
"G1"
$PN"2"35;
%"UNIVERSAL_POWER"
"1","(-2125,4100)","0","pure_quanta_power","I2";
;
HDL_POWER"P3V3_AUX"
BOM_COST"OCP3.0 "
CDS_LIB"pure_quanta_power";
"A"30;
%"GND"
"1","(-4925,3550)","5","pure_quanta_power","I20";
;
BOM_COST"MEM"
SIZE"1B"
CDS_LIB"pure_quanta_power"
HDL_POWER"GND";
"A<SIZE-1..0>\NAC"6;
%"Q_RES"
"1","(-5675,5125)","0","pure_quanta","I21";
;
LOCATION"R935"
$SEC"1"
CDS_SEC"1"
VALUE"0"
BOM_COST"MEM"
CDS_LIB"pure_quanta"
WATTAGE"1/16W"
MATERIAL"CHIP"
TOLERANCE"5%"
PACK_TYPE"0402LF"
PART_NUMBER"CS00002JB13";
"B"
$PN"2"26;
"A"
$PN"1"36;
%"Q_RES"
"1","(-5825,3500)","0","pure_quanta","I22";
;
LOCATION"R936"
$SEC"1"
CDS_SEC"1"
VALUE"0"
BOM_COST"MEM"
CDS_LIB"pure_quanta"
WATTAGE"1/16W"
MATERIAL"CHIP"
TOLERANCE"5%"
PACK_TYPE"0402LF"
PART_NUMBER"CS00002JB13";
"B"
$PN"2"35;
"A"
$PN"1"34;
%"Q_CAP"
"1","(-7200,5450)","0","pure_quanta","I24";
;
LOCATION"C218"
$SEC"1"
CDS_SEC"1"
VALUE"0.1UF"
PACK_TYPE"0402"
MATERIAL"X7R"
TOLERANCE"10%"
VOLTAGE"25V"
CDS_LIB"pure_quanta"
BOM_COST"OCP3.0 "
PART_NUMBER"CH4104K1B00";
"B"
$PN"2"7;
"A"
$PN"1"31;
%"UNIVERSAL_GND"
"1","(-7200,5250)","0","pure_quanta_power","I25";
;
BOM_COST"OCP3.0 "
CDS_LIB"pure_quanta_power"
HDL_POWER"GND";
"A"7;
%"SN74LVC1G07DBVR"
"1","(-6600,5125)","0","pure_quanta","I26";
;
LOCATION"U82"
$SEC"1"
CDS_SEC"1"
MATERIAL"IC"
VALUE"SN74LVC1G07DBVR"
PACK_TYPE"SMLF"
CDS_LIB"pure_quanta"
NEEDS_NO_SIZE"TRUE"
PART_NUMBER"AL1G0007024";
"NC"
$PN"1"0;
"Y"
$PN"4"36;
"GND"
$PN"3"8;
"A"
$PN"2"33;
"VCC"
$PN"5"31;
%"UNIVERSAL_GND"
"1","(-6850,4850)","0","pure_quanta_power","I27";
;
BOM_COST"OCP3.0 "
CDS_LIB"pure_quanta_power"
HDL_POWER"GND";
"A"8;
%"P1V0"
"1","(-7350,4125)","0","pure_quanta_power","I28";
;
HDL_POWER"P1V8_AUX"
CDS_LIB"pure_quanta_power";
"A"17;
%"Q_CAP"
"1","(-7350,3825)","0","pure_quanta","I29";
;
LOCATION"C219"
$SEC"1"
CDS_SEC"1"
MATERIAL"X7R"
PACK_TYPE"0402"
TOLERANCE"10%"
VALUE"0.1UF"
VOLTAGE"25V"
CDS_LIB"pure_quanta"
BOM_COST"OCP3.0 "
PART_NUMBER"CH4104K1B00";
"B"
$PN"2"9;
"A"
$PN"1"17;
%"Q_RES"
"1","(-2250,3450)","0","pure_quanta","I3";
;
LOCATION"R950"
$SEC"1"
CDS_SEC"1"
WATTAGE"1/16W"
MATERIAL"CHIP"
TOLERANCE"1%"
PACK_TYPE"0402LF"
VALUE"249"
CDS_LIB"pure_quanta"
PART_NUMBER"CS12492FB02";
"B"
$PN"2"30;
"A"
$PN"1"23;
%"UNIVERSAL_GND"
"1","(-7350,3625)","0","pure_quanta_power","I30";
;
BOM_COST"OCP3.0 "
CDS_LIB"pure_quanta_power"
HDL_POWER"GND";
"A"9;
%"SN74LVC1G07DBVR"
"1","(-6750,3500)","0","pure_quanta","I31";
;
LOCATION"U86"
$SEC"1"
CDS_SEC"1"
MATERIAL"IC"
VALUE"SN74LVC1G07DBVR"
PACK_TYPE"SMLF"
CDS_LIB"pure_quanta"
NEEDS_NO_SIZE"TRUE"
PART_NUMBER"AL1G0007024";
"NC"
$PN"1"0;
"Y"
$PN"4"34;
"GND"
$PN"3"10;
"A"
$PN"2"38;
"VCC"
$PN"5"17;
%"UNIVERSAL_GND"
"1","(-7000,3225)","0","pure_quanta_power","I32";
;
CDS_LIB"pure_quanta_power"
BOM_COST"OCP3.0 "
HDL_POWER"GND";
"A"10;
%"Q_RES"
"1","(-7950,5125)","0","pure_quanta","I33";
;
LOCATION"R934"
$SEC"1"
CDS_SEC"1"
VALUE"0"
BOM_COST"MEM"
CDS_LIB"pure_quanta"
WATTAGE"1/16W"
MATERIAL"CHIP"
TOLERANCE"5%"
PACK_TYPE"0402LF"
PART_NUMBER"CS00002JB13";
"B"
$PN"2"33;
"A"
$PN"1"37;
%"Q_RES"
"1","(-7950,4875)","0","pure_quanta","I34";
;
LOCATION"R941"
$SEC"1"
CDS_SEC"1"
VALUE"0"
MATERIAL"EMPTY"
PACK_TYPE"0402LF"
TOLERANCE"5%"
WATTAGE"1/16W"
CDS_LIB"pure_quanta"
PART_NUMBER"CS00002JB13";
"B"
$PN"2"33;
"A"
$PN"1"32;
%"Q_LED"
"1","(-4275,550)","2","pure_quanta","I38";
;
LOCATION"D49"
$SEC"1"
CDS_SEC"1"
COLOR"LED_BLUE"
MATERIAL"IC"
MANUF_PN"LTST-C281TBKT-5A"
PACK_TYPE"SMLF"
NEEDS_NO_SIZE"TRUE"
CDS_LIB"pure_quanta"
PART_NUMBER"BEBL0172Z00";
"A"
$PN"A"24;
"C"
$PN"C"11;
%"UNIVERSAL_GND"
"1","(-4750,375)","0","pure_quanta_power","I39";
;
CDS_LIB"pure_quanta_power"
BOM_COST"OCP3.0 "
HDL_POWER"GND";
"A"11;
%"UNIVERSAL_POWER"
"1","(-3950,5775)","0","pure_quanta_power","I4";
;
HDL_POWER"P3V3_AUX"
BOM_COST"OCP3.0 "
CDS_LIB"pure_quanta_power";
"A"12;
%"P1V0"
"1","(-2725,975)","0","pure_quanta_power","I40";
;
HDL_POWER"P5V_AUX"
CDS_LIB"pure_quanta_power";
"A"13;
%"Q_RES"
"1","(-3275,550)","0","pure_quanta","I41";
;
LOCATION"R1207"
$SEC"1"
CDS_SEC"1"
MATERIAL"CHIP"
TOLERANCE"1%"
PACK_TYPE"0402LF"
VALUE"470"
WATTAGE"1/16W"
CDS_LIB"pure_quanta"
PART_NUMBER"CS14702FB04";
"B"
$PN"2"13;
"A"
$PN"1"24;
%"Q_RES"
"1","(-3125,1975)","0","pure_quanta","I42";
;
LOCATION"R1208"
$SEC"1"
CDS_SEC"1"
MATERIAL"CHIP"
PACK_TYPE"0402LF"
TOLERANCE"1%"
VALUE"470"
WATTAGE"1/16W"
CDS_LIB"pure_quanta"
PART_NUMBER"CS14702FB04";
"B"
$PN"2"14;
"A"
$PN"1"19;
%"Q_LED"
"1","(-4125,1975)","2","pure_quanta","I43";
;
LOCATION"D46"
$SEC"1"
CDS_SEC"1"
PACK_TYPE"SMLF"
COLOR"LED_BLUE"
MATERIAL"IC"
MANUF_PN"LTST-C281TBKT-5A"
NEEDS_NO_SIZE"TRUE"
CDS_LIB"pure_quanta"
PART_NUMBER"BEBL0172Z00";
"A"
$PN"A"19;
"C"
$PN"C"18;
%"MOSFET_N_GSD"
"1","(-4875,1625)","0","pure_quanta","I44";
;
LOCATION"Q12"
$SEC"1"
CDS_SEC"1"
VALUE"NX138BK"
MATERIAL"IC"
PART_TYPE"SMLF"
CDS_LIB"pure_quanta"
CDS_LMAN_SYM_OUTLINE"-100,100,100,-100"
NEEDS_NO_SIZE"TRUE"
PART_NUMBER"BAM01380023";
"DRAIN"
$PN"D"18;
"SOURCE"
$PN"S"15;
"GATE"
$PN"G"22;
%"P1V0"
"1","(-2550,2400)","0","pure_quanta_power","I45";
;
HDL_POWER"P5V_AUX"
CDS_LIB"pure_quanta_power";
"A"14;
%"UNIVERSAL_GND"
"1","(-4850,1300)","0","pure_quanta_power","I46";
;
BOM_COST"OCP3.0 "
CDS_LIB"pure_quanta_power"
HDL_POWER"GND";
"A"15;
%"P1V0"
"1","(-7200,5750)","0","pure_quanta_power","I48";
;
HDL_POWER"P1V8_AUX"
CDS_LIB"pure_quanta_power";
"A"31;
%"Q_RES"
"2","(-3950,5425)","0","pure_quanta","I5";
;
LOCATION"R946"
$SEC"1"
CDS_SEC"1"
TOLERANCE"5%"
VALUE"4.7K"
MATERIAL"CHIP"
WATTAGE"1/16W"
PACK_TYPE"0402LF"
BOM_COST"OCP3.0 "
CDS_LIB"pure_quanta"
PART_NUMBER"CS24702JB10";
"A"
$PN"1"12;
"B"
$PN"2"28;
%"GND"
"1","(-4000,5175)","1","pure_quanta_power","I6";
;
SIZE"1B"
BOM_COST"MEM"
CDS_LIB"pure_quanta_power"
HDL_POWER"GND";
"A<SIZE-1..0>\NAC"16;
%"Q_RES"
"1","(-2000,5075)","0","pure_quanta","I7";
;
LOCATION"R948"
$SEC"1"
CDS_SEC"1"
WATTAGE"1/16W"
MATERIAL"CHIP"
TOLERANCE"1%"
PACK_TYPE"0402LF"
VALUE"130"
CDS_LIB"pure_quanta"
PART_NUMBER"CS11302FB03";
"B"
$PN"2"25;
"A"
$PN"1"29;
%"Q_LED"
"1","(-2950,5075)","2","pure_quanta","I8";
;
LOCATION"D5"
$SEC"1"
CDS_SEC"1"
MATERIAL"IC"
PACK_TYPE"SMLF"
COLOR"LED_BLUE"
MANUF_PN"LTST-C281TBKT-5A"
CDS_LIB"pure_quanta"
NEEDS_NO_SIZE"TRUE"
PART_NUMBER"BEBL0172Z00";
"A"
$PN"A"29;
"C"
$PN"C"27;
%"Q_LED"
"1","(-3100,3450)","2","pure_quanta","I9";
;
LOCATION"D6"
$SEC"1"
CDS_SEC"1"
MATERIAL"IC"
PACK_TYPE"SMLF"
COLOR"LED_YELLOW"
MANUF_PN"LTST-C190KSKT-P"
CDS_LIB"pure_quanta"
NEEDS_NO_SIZE"TRUE"
PART_NUMBER"BEYL0159Z00";
"A"
$PN"A"23;
"C"
$PN"C"21;
END.
